FILE_TYPE = CONNECTIVITY;
{Allegro Design Entry HDL 17.4-2019 S026 (4007227) 1/17/2022}
"PAGE_NUMBER" = 424;
0"NC";
END.
